(kicad_pcb
	(version 20260206)
	(generator "pcbnew")
	(generator_version "10.0")
	(general
		(thickness 1.6)
		(legacy_teardrops no)
	)
	(paper "A4")
	(title_block
		(title "Wiwynn_Tioga_Pass_MB.brd")
		(comment 1 "Tioga Pass / footprints 1663-1663 of 4770")
	)
	(layers
		(0 "F.Cu" signal "TOP")
		(4 "In1.Cu" signal "L2GND")
		(6 "In2.Cu" signal "L3")
		(8 "In3.Cu" signal "L4GND")
		(10 "In4.Cu" signal "L5")
		(12 "In5.Cu" signal "L6GND")
		(14 "In6.Cu" signal "L7VCC")
		(16 "In7.Cu" signal "L8VCC")
		(18 "In8.Cu" signal "L9GND")
		(20 "In9.Cu" signal "L10")
		(22 "In10.Cu" signal "L11GND")
		(24 "In11.Cu" signal "L12")
		(26 "In12.Cu" signal "L13GND")
		(2 "B.Cu" signal "BOTTOM")
		(9 "F.Adhes" user "F.Adhesive")
		(11 "B.Adhes" user "B.Adhesive")
		(13 "F.Paste" user "Package Geometry/Pastemask Top")
		(15 "B.Paste" user "Package Geometry/Pastemask Bottom")
		(5 "F.SilkS" user "Ref Des/Silkscreen Top")
		(7 "B.SilkS" user "Ref Des/Silkscreen Bottom")
		(1 "F.Mask" user "Board Geometry/Soldermask Top")
		(3 "B.Mask" user "Board Geometry/Soldermask Bottom")
		(17 "Dwgs.User" user "User.Drawings")
		(19 "Cmts.User" user "User.Comments")
		(21 "Eco1.User" user "User.Eco1")
		(23 "Eco2.User" user "User.Eco2")
		(25 "Edge.Cuts" user "Board Geometry/Outline")
		(27 "Margin" user)
		(31 "F.CrtYd" user "Package Geometry/Place Bound Top")
		(29 "B.CrtYd" user "Package Geometry/Place Bound Bottom")
		(35 "F.Fab" user "Ref Des/Assembly Top")
		(33 "B.Fab" user "Ref Des/Assembly Bottom")
	)
	(footprint ""
		(layer "F.Cu")
		(at 198.02221 -68.49237 90)
		(property "Reference" "C4D49"
			(at -0.8382 -0.67818 90)
			(unlocked yes)
			(layer "F.SilkS")
			(effects
				(font
					(size 0.4064 0.254)
					(thickness 0.1524)
				)
				(justify left)
			)
		)
		(property "Value" ""
			(at 0 0 90)
			(layer "F.Fab")
			(effects
				(font
					(size 1.27 1.27)
				)
			)
		)
		(duplicate_pad_numbers_are_jumpers no)
		(fp_poly
			(pts
				(xy 0.3048 -0.1016) (xy 0.3048 0.9906) (xy -0.3048 0.9906) (xy -0.3048 -0.1016)
			)
			(stroke
				(width 0)
				(type default)
			)
			(fill no)
			(layer "F.CrtYd")
		)
		(fp_line
			(start 0.3048 -0.1016)
			(end -0.3048 -0.1016)
			(stroke
				(width 0.1)
				(type default)
			)
			(layer "F.Fab")
		)
		(fp_line
			(start -0.3048 -0.1016)
			(end -0.3048 0.9906)
			(stroke
				(width 0.1)
				(type default)
			)
			(layer "F.Fab")
		)
		(fp_line
			(start 0.3048 0.9906)
			(end 0.3048 -0.1016)
			(stroke
				(width 0.1)
				(type default)
			)
			(layer "F.Fab")
		)
		(fp_line
			(start -0.3048 0.9906)
			(end 0.3048 0.9906)
			(stroke
				(width 0.1)
				(type default)
			)
			(layer "F.Fab")
		)
		(pad "1" smd rect
			(at 0 0 90)
			(size 0.508 0.508)
			(layers "F.Cu" "F.Mask" "F.Paste")
			(net "VR_FET_SW_P12V_STBY_PVCCIN_CPU0")
		)
		(pad "2" smd rect
			(at 0 0.889 90)
			(size 0.508 0.508)
			(layers "F.Cu" "F.Mask" "F.Paste")
			(net "GND")
		)
		(zone
			(layer "F.Cu")
			(hatch none 0.5)
			(connect_pads
				(clearance 0)
			)
			(min_thickness 0.25)
			(keepout
				(tracks allowed)
				(vias not_allowed)
				(pads allowed)
				(copperpour not_allowed)
				(footprints allowed)
			)
			(placement
				(enabled no)
				(sheetname "")
			)
			(fill
				(thermal_gap 0.5)
				(thermal_bridge_width 0.5)
				(island_removal_mode 0)
			)
			(polygon
				(pts
					(xy 198.27621 -68.23837) (xy 198.27621 -68.74637) (xy 198.65721 -68.74637) (xy 198.65721 -68.23837)
				)
			)
		)
		(zone
			(layer "F.Cu")
			(hatch none 0.5)
			(connect_pads
				(clearance 0)
			)
			(min_thickness 0.25)
			(keepout
				(tracks not_allowed)
				(vias allowed)
				(pads allowed)
				(copperpour not_allowed)
				(footprints allowed)
			)
			(placement
				(enabled no)
				(sheetname "")
			)
			(fill
				(thermal_gap 0.5)
				(thermal_bridge_width 0.5)
				(island_removal_mode 0)
			)
			(polygon
				(pts
					(xy 198.65721 -68.23837) (xy 198.65721 -68.74637) (xy 198.27621 -68.74637) (xy 198.27621 -68.23837)
				)
			)
		)
	)
)
